# S9S_MB_2U (Grand Teton) — schematic netlist excerpt (pin names and nets, part order shuffled) for the footprints in the layout excerpt that follows; sources: Cadence DE-HDL packaged netlist, KiCad conversion of 03242023_DA0F0TMBIJ0_F0T_Motherboard_J_brd_V01_OCP.brd

C1103  Q_CAP_DIFFBUS  DIFF BUS_0.22UF 6.3V 20% X6S  pkg C0201  page 181 : \1\ = P3E_PCH_M2_TX_DN<1> ; \2\ = P3E_PCH_M2_TX_C_DN<1>
DM13  DUMMY_SYMBOL  BATTERY_SYMBOL MECH  pkg TP30_FOR_BOM  page 312 : \1\ = NC
R4568  Q_RES  4.7K 1% CHIP  pkg 0402LF  page 250 : A = P1V581_PDB_ADC ; B = GND

(kicad_pcb
	(version 20260206)
	(generator "pcbnew")
	(generator_version "10.0")
	(general
		(thickness 1.6)
		(legacy_teardrops no)
	)
	(paper "A4")
	(title_block
		(title "03242023_DA0F0TMBIJ0_F0T_Motherboard_J_brd_V01_OCP.brd")
		(comment 1 "Grand Teton / footprints 1308-1310 of 6105")
	)
	(layers
		(0 "F.Cu" signal "TOP")
		(4 "In1.Cu" signal "GND")
		(6 "In2.Cu" signal "IN1")
		(8 "In3.Cu" signal "GND1")
		(10 "In4.Cu" signal "IN2")
		(12 "In5.Cu" signal "GND2")
		(14 "In6.Cu" signal "IN3")
		(16 "In7.Cu" signal "GND3")
		(18 "In8.Cu" signal "VCC")
		(20 "In9.Cu" signal "VCC1")
		(22 "In10.Cu" signal "GND4")
		(24 "In11.Cu" signal "IN4")
		(26 "In12.Cu" signal "GND5")
		(28 "In13.Cu" signal "IN5")
		(30 "In14.Cu" signal "GND6")
		(32 "In15.Cu" signal "IN6")
		(34 "In16.Cu" signal "GND7")
		(2 "B.Cu" signal "BOTTOM")
		(9 "F.Adhes" user "F.Adhesive")
		(11 "B.Adhes" user "B.Adhesive")
		(13 "F.Paste" user "Package Geometry/Pastemask Top")
		(15 "B.Paste" user "Package Geometry/Pastemask Bottom")
		(5 "F.SilkS" user "Ref Des/Silkscreen Top")
		(7 "B.SilkS" user "Ref Des/Silkscreen Bottom")
		(1 "F.Mask" user "Board Geometry/Soldermask Top")
		(3 "B.Mask" user "Board Geometry/Soldermask Bottom")
		(17 "Dwgs.User" user "User.Drawings")
		(19 "Cmts.User" user "User.Comments")
		(21 "Eco1.User" user "User.Eco1")
		(23 "Eco2.User" user "User.Eco2")
		(25 "Edge.Cuts" user "Board Geometry/Outline")
		(27 "Margin" user)
		(31 "F.CrtYd" user "Package Geometry/Place Bound Top")
		(29 "B.CrtYd" user "Package Geometry/Place Bound Bottom")
		(35 "F.Fab" user "Ref Des/Assembly Top")
		(33 "B.Fab" user "Ref Des/Assembly Bottom")
	)
	(footprint ""
		(layer "F.Cu")
		(at 180.528468 -50.060098 180)
		(property "Reference" "C1103"
			(at 0 0 180)
			(layer "F.SilkS")
			(hide yes)
			(effects
				(font
					(size 1.27 1.27)
				)
			)
		)
		(property "Value" ""
			(at 0 0 180)
			(layer "F.Fab")
			(effects
				(font
					(size 1.27 1.27)
				)
			)
		)
		(duplicate_pad_numbers_are_jumpers no)
		(fp_line
			(start 0.299974 0.150114)
			(end -0.299974 0.150114)
			(stroke
				(width 0.1)
				(type default)
			)
			(layer "F.Fab")
		)
		(fp_line
			(start 0.299974 -0.150114)
			(end 0.299974 0.150114)
			(stroke
				(width 0.1)
				(type default)
			)
			(layer "F.Fab")
		)
		(fp_line
			(start -0.299974 0.150114)
			(end -0.299974 -0.150114)
			(stroke
				(width 0.1)
				(type default)
			)
			(layer "F.Fab")
		)
		(fp_line
			(start -0.299974 -0.150114)
			(end 0.299974 -0.150114)
			(stroke
				(width 0.1)
				(type default)
			)
			(layer "F.Fab")
		)
		(pad "1" smd rect
			(at -0.2667 0 180)
			(size 0.3048 0.381)
			(layers "F.Cu" "F.Mask" "F.Paste")
			(net "P3E_PCH_M2_TX_DN<1>")
		)
		(pad "2" smd rect
			(at 0.2667 0 180)
			(size 0.3048 0.381)
			(layers "F.Cu" "F.Mask" "F.Paste")
			(net "P3E_PCH_M2_TX_C_DN<1>")
		)
		(zone
			(layer "In1.Cu")
			(hatch none 0.5)
			(connect_pads
				(clearance 0)
			)
			(min_thickness 0.25)
			(keepout
				(tracks not_allowed)
				(vias allowed)
				(pads allowed)
				(copperpour not_allowed)
				(footprints allowed)
			)
			(placement
				(enabled no)
				(sheetname "")
			)
			(fill
				(thermal_gap 0.5)
				(thermal_bridge_width 0.5)
				(island_removal_mode 0)
			)
			(polygon
				(pts
					(arc
						(start 180.388768 -50.301398)
						(mid 180.44265 -50.27908)
						(end 180.464968 -50.225198)
					)
					(arc
						(start 180.464968 -49.894998)
						(mid 180.44265 -49.841116)
						(end 180.388768 -49.818798)
					)
					(arc
						(start 180.134768 -49.818798)
						(mid 180.080886 -49.841116)
						(end 180.058568 -49.894998)
					)
					(arc
						(start 180.058568 -50.225198)
						(mid 180.080886 -50.27908)
						(end 180.134768 -50.301398)
					)
				)
			)
		)
		(zone
			(layer "In1.Cu")
			(hatch none 0.5)
			(connect_pads
				(clearance 0)
			)
			(min_thickness 0.25)
			(keepout
				(tracks not_allowed)
				(vias allowed)
				(pads allowed)
				(copperpour not_allowed)
				(footprints allowed)
			)
			(placement
				(enabled no)
				(sheetname "")
			)
			(fill
				(thermal_gap 0.5)
				(thermal_bridge_width 0.5)
				(island_removal_mode 0)
			)
			(polygon
				(pts
					(arc
						(start 180.922168 -50.301398)
						(mid 180.97605 -50.27908)
						(end 180.998368 -50.225198)
					)
					(arc
						(start 180.998368 -49.894998)
						(mid 180.97605 -49.841116)
						(end 180.922168 -49.818798)
					)
					(arc
						(start 180.668168 -49.818798)
						(mid 180.614286 -49.841116)
						(end 180.591968 -49.894998)
					)
					(arc
						(start 180.591968 -50.225198)
						(mid 180.614286 -50.27908)
						(end 180.668168 -50.301398)
					)
				)
			)
		)
	)
	(footprint ""
		(layer "F.Cu")
		(at 40.6146 -103.977948)
		(property "Reference" "R4568"
			(at 0 0 0)
			(layer "F.SilkS")
			(hide yes)
			(effects
				(font
					(size 1.27 1.27)
				)
			)
		)
		(property "Value" ""
			(at 0 0 0)
			(layer "F.Fab")
			(effects
				(font
					(size 1.27 1.27)
				)
			)
		)
		(duplicate_pad_numbers_are_jumpers no)
		(fp_line
			(start -0.7874 -0.4064)
			(end 0.7874 -0.4064)
			(stroke
				(width 0.1524)
				(type default)
			)
			(layer "F.SilkS")
		)
		(fp_line
			(start -0.7874 0.4064)
			(end -0.7874 -0.4064)
			(stroke
				(width 0.1524)
				(type default)
			)
			(layer "F.SilkS")
		)
		(fp_line
			(start 0.7874 -0.4064)
			(end 0.7874 0.4064)
			(stroke
				(width 0.1524)
				(type default)
			)
			(layer "F.SilkS")
		)
		(fp_line
			(start 0.7874 0.4064)
			(end -0.7874 0.4064)
			(stroke
				(width 0.1524)
				(type default)
			)
			(layer "F.SilkS")
		)
		(fp_line
			(start -0.67945 -0.305054)
			(end -0.12065 -0.305054)
			(stroke
				(width 0.1)
				(type default)
			)
			(layer "F.Fab")
		)
		(fp_line
			(start -0.67945 0.3048)
			(end -0.67945 -0.305054)
			(stroke
				(width 0.1)
				(type default)
			)
			(layer "F.Fab")
		)
		(fp_line
			(start -0.12065 -0.305054)
			(end -0.12065 -0.2794)
			(stroke
				(width 0.1)
				(type default)
			)
			(layer "F.Fab")
		)
		(fp_line
			(start -0.12065 -0.2794)
			(end 0.12065 -0.2794)
			(stroke
				(width 0.1)
				(type default)
			)
			(layer "F.Fab")
		)
		(fp_line
			(start -0.12065 0.2794)
			(end -0.12065 0.3048)
			(stroke
				(width 0.1)
				(type default)
			)
			(layer "F.Fab")
		)
		(fp_line
			(start -0.12065 0.3048)
			(end -0.67945 0.3048)
			(stroke
				(width 0.1)
				(type default)
			)
			(layer "F.Fab")
		)
		(fp_line
			(start 0.120396 0.2794)
			(end -0.12065 0.2794)
			(stroke
				(width 0.1)
				(type default)
			)
			(layer "F.Fab")
		)
		(fp_line
			(start 0.120396 0.3048)
			(end 0.120396 0.2794)
			(stroke
				(width 0.1)
				(type default)
			)
			(layer "F.Fab")
		)
		(fp_line
			(start 0.12065 -0.3048)
			(end 0.67945 -0.3048)
			(stroke
				(width 0.1)
				(type default)
			)
			(layer "F.Fab")
		)
		(fp_line
			(start 0.12065 -0.2794)
			(end 0.12065 -0.3048)
			(stroke
				(width 0.1)
				(type default)
			)
			(layer "F.Fab")
		)
		(fp_line
			(start 0.67945 -0.3048)
			(end 0.67945 0.3048)
			(stroke
				(width 0.1)
				(type default)
			)
			(layer "F.Fab")
		)
		(fp_line
			(start 0.67945 0.3048)
			(end 0.120396 0.3048)
			(stroke
				(width 0.1)
				(type default)
			)
			(layer "F.Fab")
		)
		(pad "1" smd circle
			(at -0.40005 0)
			(size 0 0)
			(layers "F.Cu" "F.Mask" "F.Paste")
			(net "P1V581_PDB_ADC")
		)
		(pad "2" smd circle
			(at 0.40005 0)
			(size 0 0)
			(layers "F.Cu" "F.Mask" "F.Paste")
			(net "GND")
		)
	)
	(footprint ""
		(layer "F.Cu")
		(at 498.89918 -467.976966)
		(property "Reference" "DM13"
			(at -0.3937 -0.588518 0)
			(unlocked yes)
			(layer "F.SilkS")
			(effects
				(font
					(size 0.254 0.127)
					(thickness 0.000001)
				)
				(justify left)
			)
		)
		(property "Value" ""
			(at 0 0 0)
			(layer "F.Fab")
			(effects
				(font
					(size 1.27 1.27)
				)
			)
		)
		(duplicate_pad_numbers_are_jumpers no)
		(pad "1" smd circle
			(at 0 0)
			(size 0.762 0.762)
			(layers "F.Cu" "F.Mask" "F.Paste")
			(net "Net_8588")
		)
	)
)
